(kicad_pcb
	(version 20260206)
	(generator "pcbnew")
	(generator_version "10.0")
	(general
		(thickness 1.6)
		(legacy_teardrops no)
	)
	(paper "A4")
	(title_block
		(title "Wiwynn_Tioga_Pass_MB.brd")
		(comment 1 "Tioga Pass / footprints 534-540 of 4770")
	)
	(layers
		(0 "F.Cu" signal "TOP")
		(4 "In1.Cu" signal "L2GND")
		(6 "In2.Cu" signal "L3")
		(8 "In3.Cu" signal "L4GND")
		(10 "In4.Cu" signal "L5")
		(12 "In5.Cu" signal "L6GND")
		(14 "In6.Cu" signal "L7VCC")
		(16 "In7.Cu" signal "L8VCC")
		(18 "In8.Cu" signal "L9GND")
		(20 "In9.Cu" signal "L10")
		(22 "In10.Cu" signal "L11GND")
		(24 "In11.Cu" signal "L12")
		(26 "In12.Cu" signal "L13GND")
		(2 "B.Cu" signal "BOTTOM")
		(9 "F.Adhes" user "F.Adhesive")
		(11 "B.Adhes" user "B.Adhesive")
		(13 "F.Paste" user "Package Geometry/Pastemask Top")
		(15 "B.Paste" user "Package Geometry/Pastemask Bottom")
		(5 "F.SilkS" user "Ref Des/Silkscreen Top")
		(7 "B.SilkS" user "Ref Des/Silkscreen Bottom")
		(1 "F.Mask" user "Board Geometry/Soldermask Top")
		(3 "B.Mask" user "Board Geometry/Soldermask Bottom")
		(17 "Dwgs.User" user "User.Drawings")
		(19 "Cmts.User" user "User.Comments")
		(21 "Eco1.User" user "User.Eco1")
		(23 "Eco2.User" user "User.Eco2")
		(25 "Edge.Cuts" user "Board Geometry/Outline")
		(27 "Margin" user)
		(31 "F.CrtYd" user "Package Geometry/Place Bound Top")
		(29 "B.CrtYd" user "Package Geometry/Place Bound Bottom")
		(35 "F.Fab" user "Ref Des/Assembly Top")
		(33 "B.Fab" user "Ref Des/Assembly Bottom")
	)
	(footprint ""
		(layer "F.Cu")
		(at 408.813 -102.9335 180)
		(property "Reference" "R8C24"
			(at 0 0 180)
			(layer "F.SilkS")
			(hide yes)
			(effects
				(font
					(size 1.27 1.27)
				)
			)
		)
		(property "Value" ""
			(at 0 0 180)
			(layer "F.Fab")
			(effects
				(font
					(size 1.27 1.27)
				)
			)
		)
		(duplicate_pad_numbers_are_jumpers no)
		(fp_poly
			(pts
				(xy -0.2794 -0.1016) (xy 0.2794 -0.1016) (xy 0.2794 0.9906) (xy -0.2794 0.9906)
			)
			(stroke
				(width 0)
				(type default)
			)
			(fill no)
			(layer "F.CrtYd")
		)
		(fp_line
			(start 0.2794 0.9906)
			(end 0.2794 -0.1016)
			(stroke
				(width 0.1)
				(type default)
			)
			(layer "F.Fab")
		)
		(fp_line
			(start 0.2794 -0.1016)
			(end -0.2794 -0.1016)
			(stroke
				(width 0.1)
				(type default)
			)
			(layer "F.Fab")
		)
		(fp_line
			(start -0.2794 0.9906)
			(end 0.2794 0.9906)
			(stroke
				(width 0.1)
				(type default)
			)
			(layer "F.Fab")
		)
		(fp_line
			(start -0.2794 -0.1016)
			(end -0.2794 0.9906)
			(stroke
				(width 0.1)
				(type default)
			)
			(layer "F.Fab")
		)
		(pad "1" smd rect
			(at 0 0 180)
			(size 0.508 0.508)
			(layers "F.Cu" "F.Mask" "F.Paste")
			(net "FM_GBE_LOM_DISABLE_N")
		)
		(pad "2" smd rect
			(at 0 0.889 180)
			(size 0.508 0.508)
			(layers "F.Cu" "F.Mask" "F.Paste")
			(net "FM_1GB_LOM_DISABLE_N")
		)
		(zone
			(layer "F.Cu")
			(hatch none 0.5)
			(connect_pads
				(clearance 0)
			)
			(min_thickness 0.25)
			(keepout
				(tracks not_allowed)
				(vias allowed)
				(pads allowed)
				(copperpour not_allowed)
				(footprints allowed)
			)
			(placement
				(enabled no)
				(sheetname "")
			)
			(fill
				(thermal_gap 0.5)
				(thermal_bridge_width 0.5)
				(island_removal_mode 0)
			)
			(polygon
				(pts
					(xy 409.067 -103.5685) (xy 408.559 -103.5685) (xy 408.559 -103.1875) (xy 409.067 -103.1875)
				)
			)
		)
		(zone
			(layer "F.Cu")
			(hatch none 0.5)
			(connect_pads
				(clearance 0)
			)
			(min_thickness 0.25)
			(keepout
				(tracks allowed)
				(vias not_allowed)
				(pads allowed)
				(copperpour not_allowed)
				(footprints allowed)
			)
			(placement
				(enabled no)
				(sheetname "")
			)
			(fill
				(thermal_gap 0.5)
				(thermal_bridge_width 0.5)
				(island_removal_mode 0)
			)
			(polygon
				(pts
					(xy 409.067 -103.1875) (xy 408.559 -103.1875) (xy 408.559 -103.5685) (xy 409.067 -103.5685)
				)
			)
		)
	)
	(footprint ""
		(layer "F.Cu")
		(at 6.35 -127.127 90)
		(property "Reference" "R1B12"
			(at -0.8382 -0.67818 90)
			(unlocked yes)
			(layer "F.SilkS")
			(effects
				(font
					(size 0.4064 0.254)
					(thickness 0.1524)
				)
				(justify left)
			)
		)
		(property "Value" ""
			(at 0 0 90)
			(layer "F.Fab")
			(effects
				(font
					(size 1.27 1.27)
				)
			)
		)
		(duplicate_pad_numbers_are_jumpers no)
		(fp_poly
			(pts
				(xy -0.2794 -0.1016) (xy 0.2794 -0.1016) (xy 0.2794 0.9906) (xy -0.2794 0.9906)
			)
			(stroke
				(width 0)
				(type default)
			)
			(fill no)
			(layer "F.CrtYd")
		)
		(fp_line
			(start 0.2794 -0.1016)
			(end -0.2794 -0.1016)
			(stroke
				(width 0.1)
				(type default)
			)
			(layer "F.Fab")
		)
		(fp_line
			(start -0.2794 -0.1016)
			(end -0.2794 0.9906)
			(stroke
				(width 0.1)
				(type default)
			)
			(layer "F.Fab")
		)
		(fp_line
			(start 0.2794 0.9906)
			(end 0.2794 -0.1016)
			(stroke
				(width 0.1)
				(type default)
			)
			(layer "F.Fab")
		)
		(fp_line
			(start -0.2794 0.9906)
			(end 0.2794 0.9906)
			(stroke
				(width 0.1)
				(type default)
			)
			(layer "F.Fab")
		)
		(pad "1" smd rect
			(at 0 0 90)
			(size 0.508 0.508)
			(layers "F.Cu" "F.Mask" "F.Paste")
			(net "VR_PVDDQ_KLM_XADDR1")
		)
		(pad "2" smd rect
			(at 0 0.889 90)
			(size 0.508 0.508)
			(layers "F.Cu" "F.Mask" "F.Paste")
			(net "GND")
		)
		(zone
			(layer "F.Cu")
			(hatch none 0.5)
			(connect_pads
				(clearance 0)
			)
			(min_thickness 0.25)
			(keepout
				(tracks allowed)
				(vias not_allowed)
				(pads allowed)
				(copperpour not_allowed)
				(footprints allowed)
			)
			(placement
				(enabled no)
				(sheetname "")
			)
			(fill
				(thermal_gap 0.5)
				(thermal_bridge_width 0.5)
				(island_removal_mode 0)
			)
			(polygon
				(pts
					(xy 6.604 -126.873) (xy 6.604 -127.381) (xy 6.985 -127.381) (xy 6.985 -126.873)
				)
			)
		)
		(zone
			(layer "F.Cu")
			(hatch none 0.5)
			(connect_pads
				(clearance 0)
			)
			(min_thickness 0.25)
			(keepout
				(tracks not_allowed)
				(vias allowed)
				(pads allowed)
				(copperpour not_allowed)
				(footprints allowed)
			)
			(placement
				(enabled no)
				(sheetname "")
			)
			(fill
				(thermal_gap 0.5)
				(thermal_bridge_width 0.5)
				(island_removal_mode 0)
			)
			(polygon
				(pts
					(xy 6.985 -126.873) (xy 6.985 -127.381) (xy 6.604 -127.381) (xy 6.604 -126.873)
				)
			)
		)
	)
	(footprint ""
		(layer "F.Cu")
		(at 40.036496 -97.671382)
		(property "Reference" "L1C1"
			(at 3.378708 -4.251706 0)
			(unlocked yes)
			(layer "F.SilkS")
			(effects
				(font
					(size 0.4064 0.254)
					(thickness 0.1524)
				)
			)
		)
		(property "Value" ""
			(at 0 0 0)
			(layer "F.Fab")
			(effects
				(font
					(size 1.27 1.27)
				)
			)
		)
		(duplicate_pad_numbers_are_jumpers no)
		(fp_line
			(start -1.1303 -3.199892)
			(end 8.3693 -3.199892)
			(stroke
				(width 0.1524)
				(type default)
			)
			(layer "F.SilkS")
		)
		(fp_line
			(start -1.1303 -1.6637)
			(end -1.1303 -3.199892)
			(stroke
				(width 0.1524)
				(type default)
			)
			(layer "F.SilkS")
		)
		(fp_line
			(start -1.1303 3.199892)
			(end -1.1303 1.6637)
			(stroke
				(width 0.1524)
				(type default)
			)
			(layer "F.SilkS")
		)
		(fp_line
			(start 8.3693 -3.199892)
			(end 8.3693 -1.6637)
			(stroke
				(width 0.1524)
				(type default)
			)
			(layer "F.SilkS")
		)
		(fp_line
			(start 8.3693 1.6637)
			(end 8.3693 3.199892)
			(stroke
				(width 0.1524)
				(type default)
			)
			(layer "F.SilkS")
		)
		(fp_line
			(start 8.3693 3.199892)
			(end -1.1303 3.199892)
			(stroke
				(width 0.1524)
				(type default)
			)
			(layer "F.SilkS")
		)
		(fp_rect
			(start -1.1303 3.199892)
			(end 8.3693 -3.199892)
			(stroke
				(width 0)
				(type default)
			)
			(fill no)
			(layer "F.CrtYd")
		)
		(fp_line
			(start -1.1303 -3.199892)
			(end 8.3693 -3.199892)
			(stroke
				(width 0.1)
				(type default)
			)
			(layer "F.Fab")
		)
		(fp_line
			(start -1.1303 3.199892)
			(end -1.1303 -3.199892)
			(stroke
				(width 0.1)
				(type default)
			)
			(layer "F.Fab")
		)
		(fp_line
			(start 8.3693 -3.199892)
			(end 8.3693 3.199892)
			(stroke
				(width 0.1)
				(type default)
			)
			(layer "F.Fab")
		)
		(fp_line
			(start 8.3693 3.199892)
			(end -1.1303 3.199892)
			(stroke
				(width 0.1)
				(type default)
			)
			(layer "F.Fab")
		)
		(pad "1" smd rect
			(at 0 0)
			(size 3.683 2.667)
			(layers "F.Cu" "F.Mask" "F.Paste")
			(net "VR_PVSA_CPU1_PHASE_SW")
		)
		(pad "2" smd rect
			(at 7.239 0)
			(size 3.683 2.667)
			(layers "F.Cu" "F.Mask" "F.Paste")
			(net "PVSA_CPU1")
		)
	)
	(footprint ""
		(layer "F.Cu")
		(at 475.2213 -138.557 90)
		(property "Reference" "Q9A2"
			(at 2.83591 -1.4351 0)
			(unlocked yes)
			(layer "F.SilkS")
			(effects
				(font
					(size 0.7874 0.5842)
					(thickness 0.1524)
				)
				(justify left)
			)
		)
		(property "Value" ""
			(at 0 0 90)
			(layer "F.Fab")
			(effects
				(font
					(size 1.27 1.27)
				)
			)
		)
		(duplicate_pad_numbers_are_jumpers no)
		(fp_circle
			(center -0.508 -0.7874)
			(end -0.508 -0.6604)
			(stroke
				(width 0.254)
				(type default)
			)
			(fill no)
			(layer "F.SilkS")
		)
		(fp_poly
			(pts
				(xy 0.2159 1.7526) (xy 1.5621 1.7526) (xy 1.5621 -0.4572) (xy 0.2159 -0.4572)
			)
			(stroke
				(width 0)
				(type default)
			)
			(fill no)
			(layer "F.CrtYd")
		)
		(fp_line
			(start 1.5621 -0.45466)
			(end 0.2159 -0.45466)
			(stroke
				(width 0.1)
				(type default)
			)
			(layer "F.Fab")
		)
		(fp_line
			(start 0.2159 -0.45466)
			(end 0.2159 1.75514)
			(stroke
				(width 0.1)
				(type default)
			)
			(layer "F.Fab")
		)
		(fp_line
			(start 1.5621 1.75514)
			(end 1.5621 -0.45466)
			(stroke
				(width 0.1)
				(type default)
			)
			(layer "F.Fab")
		)
		(fp_line
			(start 0.2159 1.75514)
			(end 1.5621 1.75514)
			(stroke
				(width 0.1)
				(type default)
			)
			(layer "F.Fab")
		)
		(fp_circle
			(center -0.508 -0.7874)
			(end -0.508 -0.6604)
			(stroke
				(width 0.254)
				(type default)
			)
			(fill no)
			(layer "F.Fab")
		)
		(pad "1" smd rect
			(at 0 0 90)
			(size 1.016 0.381)
			(layers "F.Cu" "F.Mask" "F.Paste")
			(net "GND")
		)
		(pad "2" smd rect
			(at 0 0.65024 90)
			(size 1.016 0.381)
			(layers "F.Cu" "F.Mask" "F.Paste")
			(net "FM_PWR_LED_N")
		)
		(pad "3" smd rect
			(at 0 1.30048 90)
			(size 1.016 0.381)
			(layers "F.Cu" "F.Mask" "F.Paste")
			(net "FM_PWR_LED_K")
		)
		(pad "4" smd rect
			(at 1.778 1.30048 90)
			(size 1.016 0.381)
			(layers "F.Cu" "F.Mask" "F.Paste")
			(net "GND")
		)
		(pad "5" smd rect
			(at 1.778 0.65024 90)
			(size 1.016 0.381)
			(layers "F.Cu" "F.Mask" "F.Paste")
			(net "FM_PWR_LED")
		)
		(pad "6" smd rect
			(at 1.778 0 90)
			(size 1.016 0.381)
			(layers "F.Cu" "F.Mask" "F.Paste")
			(net "FM_PWR_LED")
		)
		(zone
			(layer "F.Cu")
			(hatch none 0.5)
			(connect_pads
				(clearance 0)
			)
			(min_thickness 0.25)
			(keepout
				(tracks allowed)
				(vias not_allowed)
				(pads allowed)
				(copperpour not_allowed)
				(footprints allowed)
			)
			(placement
				(enabled no)
				(sheetname "")
			)
			(fill
				(thermal_gap 0.5)
				(thermal_bridge_width 0.5)
				(island_removal_mode 0)
			)
			(polygon
				(pts
					(xy 475.0308 -139.827) (xy 475.0308 -140.843) (xy 476.7199 -140.843) (xy 476.7199 -139.827)
				)
			)
		)
		(zone
			(layer "F.Cu")
			(hatch none 0.5)
			(connect_pads
				(clearance 0)
			)
			(min_thickness 0.25)
			(keepout
				(tracks allowed)
				(vias not_allowed)
				(pads allowed)
				(copperpour not_allowed)
				(footprints allowed)
			)
			(placement
				(enabled no)
				(sheetname "")
			)
			(fill
				(thermal_gap 0.5)
				(thermal_bridge_width 0.5)
				(island_removal_mode 0)
			)
			(polygon
				(pts
					(xy 475.0308 -138.049) (xy 475.0308 -139.065) (xy 476.7199 -139.065) (xy 476.7199 -138.049)
				)
			)
		)
	)
	(footprint ""
		(layer "F.Cu")
		(at 94.447868 -140.100812 90)
		(property "Reference" "C2A16"
			(at 0 0 90)
			(layer "F.SilkS")
			(hide yes)
			(effects
				(font
					(size 1.27 1.27)
				)
			)
		)
		(property "Value" ""
			(at 0 0 90)
			(layer "F.Fab")
			(effects
				(font
					(size 1.27 1.27)
				)
			)
		)
		(duplicate_pad_numbers_are_jumpers no)
		(fp_poly
			(pts
				(xy -0.7239 -0.2159) (xy 0.7239 -0.2159) (xy 0.7239 1.9939) (xy -0.7239 1.9939)
			)
			(stroke
				(width 0)
				(type default)
			)
			(fill no)
			(layer "F.CrtYd")
		)
		(fp_line
			(start 0.7239 -0.2159)
			(end -0.7239 -0.2159)
			(stroke
				(width 0.1)
				(type default)
			)
			(layer "F.Fab")
		)
		(fp_line
			(start -0.7239 -0.2159)
			(end -0.7239 1.9939)
			(stroke
				(width 0.1)
				(type default)
			)
			(layer "F.Fab")
		)
		(fp_line
			(start 0.7239 1.9939)
			(end 0.7239 -0.2159)
			(stroke
				(width 0.1)
				(type default)
			)
			(layer "F.Fab")
		)
		(fp_line
			(start -0.7239 1.9939)
			(end 0.7239 1.9939)
			(stroke
				(width 0.1)
				(type default)
			)
			(layer "F.Fab")
		)
		(pad "1" smd rect
			(at 0 0 90)
			(size 1.27 1.016)
			(layers "F.Cu" "F.Mask" "F.Paste")
			(net "PVDDQ_KLM")
		)
		(pad "2" smd rect
			(at 0 1.778 90)
			(size 1.27 1.016)
			(layers "F.Cu" "F.Mask" "F.Paste")
			(net "GND")
		)
		(zone
			(layer "F.Cu")
			(hatch none 0.5)
			(connect_pads
				(clearance 0)
			)
			(min_thickness 0.25)
			(keepout
				(tracks not_allowed)
				(vias allowed)
				(pads allowed)
				(copperpour not_allowed)
				(footprints allowed)
			)
			(placement
				(enabled no)
				(sheetname "")
			)
			(fill
				(thermal_gap 0.5)
				(thermal_bridge_width 0.5)
				(island_removal_mode 0)
			)
			(polygon
				(pts
					(xy 94.955868 -139.465812) (xy 94.955868 -140.735812) (xy 95.717868 -140.735812) (xy 95.717868 -139.465812)
				)
			)
		)
	)
	(footprint ""
		(layer "F.Cu")
		(at 349.631 -133.223 180)
		(property "Reference" "C7B5"
			(at 0 0 180)
			(layer "F.SilkS")
			(hide yes)
			(effects
				(font
					(size 1.27 1.27)
				)
			)
		)
		(property "Value" ""
			(at 0 0 180)
			(layer "F.Fab")
			(effects
				(font
					(size 1.27 1.27)
				)
			)
		)
		(duplicate_pad_numbers_are_jumpers no)
		(fp_poly
			(pts
				(xy -0.7239 -0.2159) (xy 0.7239 -0.2159) (xy 0.7239 1.9939) (xy -0.7239 1.9939)
			)
			(stroke
				(width 0)
				(type default)
			)
			(fill no)
			(layer "F.CrtYd")
		)
		(fp_line
			(start 0.7239 1.9939)
			(end 0.7239 -0.2159)
			(stroke
				(width 0.1)
				(type default)
			)
			(layer "F.Fab")
		)
		(fp_line
			(start 0.7239 -0.2159)
			(end -0.7239 -0.2159)
			(stroke
				(width 0.1)
				(type default)
			)
			(layer "F.Fab")
		)
		(fp_line
			(start -0.7239 1.9939)
			(end 0.7239 1.9939)
			(stroke
				(width 0.1)
				(type default)
			)
			(layer "F.Fab")
		)
		(fp_line
			(start -0.7239 -0.2159)
			(end -0.7239 1.9939)
			(stroke
				(width 0.1)
				(type default)
			)
			(layer "F.Fab")
		)
		(pad "1" smd rect
			(at 0 0 180)
			(size 1.27 1.016)
			(layers "F.Cu" "F.Mask" "F.Paste")
			(net "VR_FET_SW_P12V_STBY_PVPP_DEF")
		)
		(pad "2" smd rect
			(at 0 1.778 180)
			(size 1.27 1.016)
			(layers "F.Cu" "F.Mask" "F.Paste")
			(net "GND")
		)
		(zone
			(layer "F.Cu")
			(hatch none 0.5)
			(connect_pads
				(clearance 0)
			)
			(min_thickness 0.25)
			(keepout
				(tracks not_allowed)
				(vias allowed)
				(pads allowed)
				(copperpour not_allowed)
				(footprints allowed)
			)
			(placement
				(enabled no)
				(sheetname "")
			)
			(fill
				(thermal_gap 0.5)
				(thermal_bridge_width 0.5)
				(island_removal_mode 0)
			)
			(polygon
				(pts
					(xy 350.266 -133.731) (xy 348.996 -133.731) (xy 348.996 -134.493) (xy 350.266 -134.493)
				)
			)
		)
	)
	(footprint ""
		(layer "F.Cu")
		(at 184.2516 -75.4253 180)
		(property "Reference" "C4D17"
			(at 0 0 180)
			(layer "F.SilkS")
			(hide yes)
			(effects
				(font
					(size 1.27 1.27)
				)
			)
		)
		(property "Value" ""
			(at 0 0 180)
			(layer "F.Fab")
			(effects
				(font
					(size 1.27 1.27)
				)
			)
		)
		(duplicate_pad_numbers_are_jumpers no)
		(fp_rect
			(start 0.3048 -0.1016)
			(end -0.3048 0.9906)
			(stroke
				(width 0)
				(type default)
			)
			(fill no)
			(layer "F.CrtYd")
		)
		(fp_line
			(start 0.3048 0.9906)
			(end 0.3048 -0.1016)
			(stroke
				(width 0.1)
				(type default)
			)
			(layer "F.Fab")
		)
		(fp_line
			(start 0.3048 -0.1016)
			(end -0.3048 -0.1016)
			(stroke
				(width 0.1)
				(type default)
			)
			(layer "F.Fab")
		)
		(fp_line
			(start -0.3048 0.9906)
			(end 0.3048 0.9906)
			(stroke
				(width 0.1)
				(type default)
			)
			(layer "F.Fab")
		)
		(fp_line
			(start -0.3048 -0.1016)
			(end -0.3048 0.9906)
			(stroke
				(width 0.1)
				(type default)
			)
			(layer "F.Fab")
		)
		(pad "1" smd rect
			(at 0 0 180)
			(size 0.508 0.508)
			(layers "F.Cu" "F.Mask" "F.Paste")
			(net "A_TSENSE_PVCCIN_CPU0")
		)
		(pad "2" smd rect
			(at 0 0.889 180)
			(size 0.508 0.508)
			(layers "F.Cu" "F.Mask" "F.Paste")
			(net "GND")
		)
		(zone
			(layer "F.Cu")
			(hatch none 0.5)
			(connect_pads
				(clearance 0)
			)
			(min_thickness 0.25)
			(keepout
				(tracks not_allowed)
				(vias allowed)
				(pads allowed)
				(copperpour not_allowed)
				(footprints allowed)
			)
			(placement
				(enabled no)
				(sheetname "")
			)
			(fill
				(thermal_gap 0.5)
				(thermal_bridge_width 0.5)
				(island_removal_mode 0)
			)
			(polygon
				(pts
					(xy 183.9976 -75.6793) (xy 184.5056 -75.6793) (xy 184.5056 -76.0603) (xy 183.9976 -76.0603)
				)
			)
		)
		(zone
			(layer "F.Cu")
			(hatch none 0.5)
			(connect_pads
				(clearance 0)
			)
			(min_thickness 0.25)
			(keepout
				(tracks allowed)
				(vias not_allowed)
				(pads allowed)
				(copperpour not_allowed)
				(footprints allowed)
			)
			(placement
				(enabled no)
				(sheetname "")
			)
			(fill
				(thermal_gap 0.5)
				(thermal_bridge_width 0.5)
				(island_removal_mode 0)
			)
			(polygon
				(pts
					(xy 183.9976 -75.6793) (xy 184.5056 -75.6793) (xy 184.5056 -76.0603) (xy 183.9976 -76.0603)
				)
			)
		)
	)
)
